# S9S_MB_2U (Grand Teton) — schematic netlist excerpt (pin names and nets, part order shuffled) for the footprints in the layout excerpt that follows; sources: Cadence DE-HDL packaged netlist, KiCad conversion of 03242023_DA0F0TMBIJ0_F0T_Motherboard_J_brd_V01_OCP.brd

R2987  Q_RES  0 5% EMPTY  pkg 0402LF  page 234 : A = SMB_2_BMC_GPU_R_SDA ; B = SMB_2_BMC_GPU_BUF_R_SDA
R1751  Q_RES  33.2 1% CHIP  pkg 0402LF  page 222 : A = SGPIO_DO_0 ; B = SGPIO_DEBUG_PLD_DOUT

(kicad_pcb
	(version 20260206)
	(generator "pcbnew")
	(generator_version "10.0")
	(general
		(thickness 1.6)
		(legacy_teardrops no)
	)
	(paper "A4")
	(title_block
		(title "03242023_DA0F0TMBIJ0_F0T_Motherboard_J_brd_V01_OCP.brd")
		(comment 1 "Grand Teton / footprints 556-557 of 6105")
	)
	(layers
		(0 "F.Cu" signal "TOP")
		(4 "In1.Cu" signal "GND")
		(6 "In2.Cu" signal "IN1")
		(8 "In3.Cu" signal "GND1")
		(10 "In4.Cu" signal "IN2")
		(12 "In5.Cu" signal "GND2")
		(14 "In6.Cu" signal "IN3")
		(16 "In7.Cu" signal "GND3")
		(18 "In8.Cu" signal "VCC")
		(20 "In9.Cu" signal "VCC1")
		(22 "In10.Cu" signal "GND4")
		(24 "In11.Cu" signal "IN4")
		(26 "In12.Cu" signal "GND5")
		(28 "In13.Cu" signal "IN5")
		(30 "In14.Cu" signal "GND6")
		(32 "In15.Cu" signal "IN6")
		(34 "In16.Cu" signal "GND7")
		(2 "B.Cu" signal "BOTTOM")
		(9 "F.Adhes" user "F.Adhesive")
		(11 "B.Adhes" user "B.Adhesive")
		(13 "F.Paste" user "Package Geometry/Pastemask Top")
		(15 "B.Paste" user "Package Geometry/Pastemask Bottom")
		(5 "F.SilkS" user "Ref Des/Silkscreen Top")
		(7 "B.SilkS" user "Ref Des/Silkscreen Bottom")
		(1 "F.Mask" user "Board Geometry/Soldermask Top")
		(3 "B.Mask" user "Board Geometry/Soldermask Bottom")
		(17 "Dwgs.User" user "User.Drawings")
		(19 "Cmts.User" user "User.Comments")
		(21 "Eco1.User" user "User.Eco1")
		(23 "Eco2.User" user "User.Eco2")
		(25 "Edge.Cuts" user "Board Geometry/Outline")
		(27 "Margin" user)
		(31 "F.CrtYd" user "Package Geometry/Place Bound Top")
		(29 "B.CrtYd" user "Package Geometry/Place Bound Bottom")
		(35 "F.Fab" user "Ref Des/Assembly Top")
		(33 "B.Fab" user "Ref Des/Assembly Bottom")
	)
	(footprint ""
		(layer "F.Cu")
		(at 34.177478 -439.339228 -90)
		(property "Reference" "R2987"
			(at 0 0 270)
			(layer "F.SilkS")
			(hide yes)
			(effects
				(font
					(size 1.27 1.27)
				)
			)
		)
		(property "Value" ""
			(at 0 0 270)
			(layer "F.Fab")
			(effects
				(font
					(size 1.27 1.27)
				)
			)
		)
		(duplicate_pad_numbers_are_jumpers no)
		(fp_line
			(start -0.7874 0.4064)
			(end -0.7874 -0.4064)
			(stroke
				(width 0.1524)
				(type default)
			)
			(layer "F.SilkS")
		)
		(fp_line
			(start 0.7874 0.4064)
			(end -0.7874 0.4064)
			(stroke
				(width 0.1524)
				(type default)
			)
			(layer "F.SilkS")
		)
		(fp_line
			(start -0.7874 -0.4064)
			(end 0.7874 -0.4064)
			(stroke
				(width 0.1524)
				(type default)
			)
			(layer "F.SilkS")
		)
		(fp_line
			(start 0.7874 -0.4064)
			(end 0.7874 0.4064)
			(stroke
				(width 0.1524)
				(type default)
			)
			(layer "F.SilkS")
		)
		(fp_line
			(start -0.67945 0.3048)
			(end -0.67945 -0.305054)
			(stroke
				(width 0.1)
				(type default)
			)
			(layer "F.Fab")
		)
		(fp_line
			(start -0.12065 0.3048)
			(end -0.67945 0.3048)
			(stroke
				(width 0.1)
				(type default)
			)
			(layer "F.Fab")
		)
		(fp_line
			(start 0.120396 0.3048)
			(end 0.120396 0.2794)
			(stroke
				(width 0.1)
				(type default)
			)
			(layer "F.Fab")
		)
		(fp_line
			(start 0.67945 0.3048)
			(end 0.120396 0.3048)
			(stroke
				(width 0.1)
				(type default)
			)
			(layer "F.Fab")
		)
		(fp_line
			(start -0.12065 0.2794)
			(end -0.12065 0.3048)
			(stroke
				(width 0.1)
				(type default)
			)
			(layer "F.Fab")
		)
		(fp_line
			(start 0.120396 0.2794)
			(end -0.12065 0.2794)
			(stroke
				(width 0.1)
				(type default)
			)
			(layer "F.Fab")
		)
		(fp_line
			(start -0.12065 -0.2794)
			(end 0.12065 -0.2794)
			(stroke
				(width 0.1)
				(type default)
			)
			(layer "F.Fab")
		)
		(fp_line
			(start 0.12065 -0.2794)
			(end 0.12065 -0.3048)
			(stroke
				(width 0.1)
				(type default)
			)
			(layer "F.Fab")
		)
		(fp_line
			(start 0.12065 -0.3048)
			(end 0.67945 -0.3048)
			(stroke
				(width 0.1)
				(type default)
			)
			(layer "F.Fab")
		)
		(fp_line
			(start 0.67945 -0.3048)
			(end 0.67945 0.3048)
			(stroke
				(width 0.1)
				(type default)
			)
			(layer "F.Fab")
		)
		(fp_line
			(start -0.67945 -0.305054)
			(end -0.12065 -0.305054)
			(stroke
				(width 0.1)
				(type default)
			)
			(layer "F.Fab")
		)
		(fp_line
			(start -0.12065 -0.305054)
			(end -0.12065 -0.2794)
			(stroke
				(width 0.1)
				(type default)
			)
			(layer "F.Fab")
		)
		(pad "1" smd circle
			(at -0.40005 0 270)
			(size 0 0)
			(layers "F.Cu" "F.Mask" "F.Paste")
			(net "SMB_2_BMC_GPU_R_SDA")
		)
		(pad "2" smd circle
			(at 0.40005 0 270)
			(size 0 0)
			(layers "F.Cu" "F.Mask" "F.Paste")
			(net "SMB_2_BMC_GPU_BUF_R_SDA")
		)
	)
	(footprint ""
		(layer "F.Cu")
		(at 160.782 -103.342948)
		(property "Reference" "R1751"
			(at 0 0 0)
			(layer "F.SilkS")
			(hide yes)
			(effects
				(font
					(size 1.27 1.27)
				)
			)
		)
		(property "Value" ""
			(at 0 0 0)
			(layer "F.Fab")
			(effects
				(font
					(size 1.27 1.27)
				)
			)
		)
		(duplicate_pad_numbers_are_jumpers no)
		(fp_line
			(start -0.7874 -0.4064)
			(end 0.7874 -0.4064)
			(stroke
				(width 0.1524)
				(type default)
			)
			(layer "F.SilkS")
		)
		(fp_line
			(start -0.7874 0.4064)
			(end -0.7874 -0.4064)
			(stroke
				(width 0.1524)
				(type default)
			)
			(layer "F.SilkS")
		)
		(fp_line
			(start 0.7874 -0.4064)
			(end 0.7874 0.4064)
			(stroke
				(width 0.1524)
				(type default)
			)
			(layer "F.SilkS")
		)
		(fp_line
			(start 0.7874 0.4064)
			(end -0.7874 0.4064)
			(stroke
				(width 0.1524)
				(type default)
			)
			(layer "F.SilkS")
		)
		(fp_line
			(start -0.67945 -0.305054)
			(end -0.12065 -0.305054)
			(stroke
				(width 0.1)
				(type default)
			)
			(layer "F.Fab")
		)
		(fp_line
			(start -0.67945 0.3048)
			(end -0.67945 -0.305054)
			(stroke
				(width 0.1)
				(type default)
			)
			(layer "F.Fab")
		)
		(fp_line
			(start -0.12065 -0.305054)
			(end -0.12065 -0.2794)
			(stroke
				(width 0.1)
				(type default)
			)
			(layer "F.Fab")
		)
		(fp_line
			(start -0.12065 -0.2794)
			(end 0.12065 -0.2794)
			(stroke
				(width 0.1)
				(type default)
			)
			(layer "F.Fab")
		)
		(fp_line
			(start -0.12065 0.2794)
			(end -0.12065 0.3048)
			(stroke
				(width 0.1)
				(type default)
			)
			(layer "F.Fab")
		)
		(fp_line
			(start -0.12065 0.3048)
			(end -0.67945 0.3048)
			(stroke
				(width 0.1)
				(type default)
			)
			(layer "F.Fab")
		)
		(fp_line
			(start 0.120396 0.2794)
			(end -0.12065 0.2794)
			(stroke
				(width 0.1)
				(type default)
			)
			(layer "F.Fab")
		)
		(fp_line
			(start 0.120396 0.3048)
			(end 0.120396 0.2794)
			(stroke
				(width 0.1)
				(type default)
			)
			(layer "F.Fab")
		)
		(fp_line
			(start 0.12065 -0.3048)
			(end 0.67945 -0.3048)
			(stroke
				(width 0.1)
				(type default)
			)
			(layer "F.Fab")
		)
		(fp_line
			(start 0.12065 -0.2794)
			(end 0.12065 -0.3048)
			(stroke
				(width 0.1)
				(type default)
			)
			(layer "F.Fab")
		)
		(fp_line
			(start 0.67945 -0.3048)
			(end 0.67945 0.3048)
			(stroke
				(width 0.1)
				(type default)
			)
			(layer "F.Fab")
		)
		(fp_line
			(start 0.67945 0.3048)
			(end 0.120396 0.3048)
			(stroke
				(width 0.1)
				(type default)
			)
			(layer "F.Fab")
		)
		(pad "1" smd circle
			(at -0.40005 0)
			(size 0 0)
			(layers "F.Cu" "F.Mask" "F.Paste")
			(net "SGPIO_DO_0")
		)
		(pad "2" smd circle
			(at 0.40005 0)
			(size 0 0)
			(layers "F.Cu" "F.Mask" "F.Paste")
			(net "SGPIO_DEBUG_PLD_DOUT")
		)
	)
)
